(kicad_pcb
	(version 20260206)
	(generator "pcbnew")
	(generator_version "10.0")
	(general
		(thickness 1.6)
		(legacy_teardrops no)
	)
	(paper "A4")
	(title_block
		(title "04192023_DAF0TMB3IC0_F0TG_MB_C_brd_V02_OCP.brd")
		(comment 1 "Grand Teton / footprints 6166-6172 of 8354")
	)
	(layers
		(0 "F.Cu" signal "TOP")
		(4 "In1.Cu" signal "GND")
		(6 "In2.Cu" signal "IN1")
		(8 "In3.Cu" signal "GND1")
		(10 "In4.Cu" signal "IN2")
		(12 "In5.Cu" signal "GND2")
		(14 "In6.Cu" signal "IN3")
		(16 "In7.Cu" signal "GND3")
		(18 "In8.Cu" signal "VCC")
		(20 "In9.Cu" signal "VCC1")
		(22 "In10.Cu" signal "GND4")
		(24 "In11.Cu" signal "IN4")
		(26 "In12.Cu" signal "GND5")
		(28 "In13.Cu" signal "IN5")
		(30 "In14.Cu" signal "GND6")
		(32 "In15.Cu" signal "IN6")
		(34 "In16.Cu" signal "GND7")
		(2 "B.Cu" signal "BOTTOM")
		(9 "F.Adhes" user "F.Adhesive")
		(11 "B.Adhes" user "B.Adhesive")
		(13 "F.Paste" user "Package Geometry/Pastemask Top")
		(15 "B.Paste" user "Package Geometry/Pastemask Bottom")
		(5 "F.SilkS" user "Ref Des/Silkscreen Top")
		(7 "B.SilkS" user "Ref Des/Silkscreen Bottom")
		(1 "F.Mask" user "Board Geometry/Soldermask Top")
		(3 "B.Mask" user "Board Geometry/Soldermask Bottom")
		(17 "Dwgs.User" user "User.Drawings")
		(19 "Cmts.User" user "User.Comments")
		(21 "Eco1.User" user "User.Eco1")
		(23 "Eco2.User" user "User.Eco2")
		(25 "Edge.Cuts" user "Board Geometry/Outline")
		(27 "Margin" user)
		(31 "F.CrtYd" user "Package Geometry/Place Bound Top")
		(29 "B.CrtYd" user "Package Geometry/Place Bound Bottom")
		(35 "F.Fab" user "Ref Des/Assembly Top")
		(33 "B.Fab" user "Ref Des/Assembly Bottom")
	)
	(footprint ""
		(layer "B.Cu")
		(at 372.313454 -262.824976)
		(property "Reference" "C2538"
			(at 0 0 0)
			(layer "B.SilkS")
			(hide yes)
			(effects
				(font
					(size 1.27 1.27)
				)
				(justify mirror)
			)
		)
		(property "Value" ""
			(at 0 0 0)
			(layer "B.Fab")
			(effects
				(font
					(size 1.27 1.27)
				)
				(justify mirror)
			)
		)
		(duplicate_pad_numbers_are_jumpers no)
		(fp_line
			(start -0.7874 -0.4064)
			(end -0.7874 0.4064)
			(stroke
				(width 0.1524)
				(type default)
			)
			(layer "B.SilkS")
		)
		(fp_line
			(start -0.7874 0.4064)
			(end 0.7874 0.4064)
			(stroke
				(width 0.1524)
				(type default)
			)
			(layer "B.SilkS")
		)
		(fp_line
			(start 0.7874 -0.4064)
			(end -0.7874 -0.4064)
			(stroke
				(width 0.1524)
				(type default)
			)
			(layer "B.SilkS")
		)
		(fp_line
			(start 0.7874 0.4064)
			(end 0.7874 -0.4064)
			(stroke
				(width 0.1524)
				(type default)
			)
			(layer "B.SilkS")
		)
		(fp_line
			(start -0.67945 -0.3048)
			(end -0.67945 0.3048)
			(stroke
				(width 0.1)
				(type default)
			)
			(layer "B.Fab")
		)
		(fp_line
			(start -0.67945 0.3048)
			(end -0.120396 0.3048)
			(stroke
				(width 0.1)
				(type default)
			)
			(layer "B.Fab")
		)
		(fp_line
			(start -0.12065 -0.3048)
			(end -0.67945 -0.3048)
			(stroke
				(width 0.1)
				(type default)
			)
			(layer "B.Fab")
		)
		(fp_line
			(start -0.12065 -0.2794)
			(end -0.12065 -0.3048)
			(stroke
				(width 0.1)
				(type default)
			)
			(layer "B.Fab")
		)
		(fp_line
			(start -0.120396 0.2794)
			(end 0.12065 0.2794)
			(stroke
				(width 0.1)
				(type default)
			)
			(layer "B.Fab")
		)
		(fp_line
			(start -0.120396 0.3048)
			(end -0.120396 0.2794)
			(stroke
				(width 0.1)
				(type default)
			)
			(layer "B.Fab")
		)
		(fp_line
			(start 0.12065 -0.305054)
			(end 0.12065 -0.2794)
			(stroke
				(width 0.1)
				(type default)
			)
			(layer "B.Fab")
		)
		(fp_line
			(start 0.12065 -0.2794)
			(end -0.12065 -0.2794)
			(stroke
				(width 0.1)
				(type default)
			)
			(layer "B.Fab")
		)
		(fp_line
			(start 0.12065 0.2794)
			(end 0.12065 0.3048)
			(stroke
				(width 0.1)
				(type default)
			)
			(layer "B.Fab")
		)
		(fp_line
			(start 0.12065 0.3048)
			(end 0.67945 0.3048)
			(stroke
				(width 0.1)
				(type default)
			)
			(layer "B.Fab")
		)
		(fp_line
			(start 0.67945 -0.305054)
			(end 0.12065 -0.305054)
			(stroke
				(width 0.1)
				(type default)
			)
			(layer "B.Fab")
		)
		(fp_line
			(start 0.67945 0.3048)
			(end 0.67945 -0.305054)
			(stroke
				(width 0.1)
				(type default)
			)
			(layer "B.Fab")
		)
		(pad "1" smd circle
			(at 0.40005 0 180)
			(size 0 0)
			(layers "B.Cu" "B.Mask" "B.Paste")
			(net "PVDDCR_SOC_P0")
		)
		(pad "2" smd circle
			(at -0.40005 0 180)
			(size 0 0)
			(layers "B.Cu" "B.Mask" "B.Paste")
			(net "GND")
		)
	)
	(footprint ""
		(layer "B.Cu")
		(at 453.921622 -390.417558 -90)
		(property "Reference" "PC6812"
			(at -0.107442 -2.997708 270)
			(unlocked yes)
			(layer "B.SilkS")
			(effects
				(font
					(size 0.7874 0.5842)
					(thickness 0.1524)
				)
				(justify left mirror)
			)
		)
		(property "Value" ""
			(at 0 0 90)
			(layer "B.Fab")
			(effects
				(font
					(size 1.27 1.27)
				)
				(justify mirror)
			)
		)
		(duplicate_pad_numbers_are_jumpers no)
		(fp_line
			(start 4.83108 2.150364)
			(end 4.447794 2.149348)
			(stroke
				(width 0.1524)
				(type default)
			)
			(layer "B.SilkS")
		)
		(fp_line
			(start -4.53898 2.15011)
			(end 4.53898 2.15011)
			(stroke
				(width 0.1524)
				(type default)
			)
			(layer "B.SilkS")
		)
		(fp_line
			(start 4.53898 2.15011)
			(end 4.53898 -2.15011)
			(stroke
				(width 0.1524)
				(type default)
			)
			(layer "B.SilkS")
		)
		(fp_line
			(start -4.53898 -2.15011)
			(end -4.53898 2.15011)
			(stroke
				(width 0.1524)
				(type default)
			)
			(layer "B.SilkS")
		)
		(fp_line
			(start 4.53898 -2.15011)
			(end -4.53898 -2.15011)
			(stroke
				(width 0.1524)
				(type default)
			)
			(layer "B.SilkS")
		)
		(fp_line
			(start 4.53898 -2.150618)
			(end 4.539742 2.152142)
			(stroke
				(width 0.1524)
				(type default)
			)
			(layer "B.SilkS")
		)
		(fp_line
			(start 4.69138 -2.150618)
			(end 4.692396 2.161032)
			(stroke
				(width 0.1524)
				(type default)
			)
			(layer "B.SilkS")
		)
		(fp_line
			(start 4.84378 -2.150618)
			(end 4.842256 2.163064)
			(stroke
				(width 0.1524)
				(type default)
			)
			(layer "B.SilkS")
		)
		(fp_line
			(start 4.84378 -2.150618)
			(end 4.53898 -2.150618)
			(stroke
				(width 0.1524)
				(type default)
			)
			(layer "B.SilkS")
		)
		(fp_line
			(start -3.64998 2.15011)
			(end 3.64998 2.15011)
			(stroke
				(width 0.1)
				(type default)
			)
			(layer "B.Fab")
		)
		(fp_line
			(start 3.64998 2.15011)
			(end 3.64998 -2.15011)
			(stroke
				(width 0.1)
				(type default)
			)
			(layer "B.Fab")
		)
		(fp_line
			(start -3.64998 -2.15011)
			(end -3.64998 2.15011)
			(stroke
				(width 0.1)
				(type default)
			)
			(layer "B.Fab")
		)
		(fp_line
			(start 3.64998 -2.15011)
			(end -3.64998 -2.15011)
			(stroke
				(width 0.1)
				(type default)
			)
			(layer "B.Fab")
		)
		(fp_text user "-"
			(at -4.585716 2.04216 270)
			(unlocked yes)
			(layer "B.SilkS")
			(effects
				(font
					(size 1.905 1.4224)
					(thickness 0.1524)
				)
				(justify left mirror)
			)
		)
		(fp_text user "+"
			(at 5.572506 -4.343908 270)
			(unlocked yes)
			(layer "B.SilkS")
			(effects
				(font
					(size 1.905 1.4224)
					(thickness 0.1524)
				)
				(justify left mirror)
			)
		)
		(fp_text user "-"
			(at -4.313174 -0.094488 270)
			(unlocked yes)
			(layer "B.Fab")
			(effects
				(font
					(size 1.905 1.4224)
					(thickness 0.1524)
				)
				(justify left mirror)
			)
		)
		(fp_text user "+"
			(at 6.214872 -0.337058 270)
			(unlocked yes)
			(layer "B.Fab")
			(effects
				(font
					(size 1.905 1.4224)
					(thickness 0.1524)
				)
				(justify left mirror)
			)
		)
		(pad "1" smd rect
			(at 3.199892 0 90)
			(size 2.413 2.8194)
			(layers "B.Cu" "B.Mask" "B.Paste")
			(net "P0V9_CPU0_RT_2D")
		)
		(pad "2" smd rect
			(at -3.199892 0 90)
			(size 2.413 2.8194)
			(layers "B.Cu" "B.Mask" "B.Paste")
			(net "GND")
		)
	)
	(footprint ""
		(layer "B.Cu")
		(at 18.838926 -97.330768 -90)
		(property "Reference" "R3655"
			(at 0 0 90)
			(layer "B.SilkS")
			(hide yes)
			(effects
				(font
					(size 1.27 1.27)
				)
				(justify mirror)
			)
		)
		(property "Value" ""
			(at 0 0 90)
			(layer "B.Fab")
			(effects
				(font
					(size 1.27 1.27)
				)
				(justify mirror)
			)
		)
		(duplicate_pad_numbers_are_jumpers no)
		(fp_line
			(start -0.7874 0.4064)
			(end 0.7874 0.4064)
			(stroke
				(width 0.1524)
				(type default)
			)
			(layer "B.SilkS")
		)
		(fp_line
			(start 0.7874 0.4064)
			(end 0.7874 -0.4064)
			(stroke
				(width 0.1524)
				(type default)
			)
			(layer "B.SilkS")
		)
		(fp_line
			(start -0.7874 -0.4064)
			(end -0.7874 0.4064)
			(stroke
				(width 0.1524)
				(type default)
			)
			(layer "B.SilkS")
		)
		(fp_line
			(start 0.7874 -0.4064)
			(end -0.7874 -0.4064)
			(stroke
				(width 0.1524)
				(type default)
			)
			(layer "B.SilkS")
		)
		(fp_line
			(start -0.67945 0.3048)
			(end -0.120396 0.3048)
			(stroke
				(width 0.1)
				(type default)
			)
			(layer "B.Fab")
		)
		(fp_line
			(start -0.120396 0.3048)
			(end -0.120396 0.2794)
			(stroke
				(width 0.1)
				(type default)
			)
			(layer "B.Fab")
		)
		(fp_line
			(start 0.12065 0.3048)
			(end 0.67945 0.3048)
			(stroke
				(width 0.1)
				(type default)
			)
			(layer "B.Fab")
		)
		(fp_line
			(start 0.67945 0.3048)
			(end 0.67945 -0.305054)
			(stroke
				(width 0.1)
				(type default)
			)
			(layer "B.Fab")
		)
		(fp_line
			(start -0.120396 0.2794)
			(end 0.12065 0.2794)
			(stroke
				(width 0.1)
				(type default)
			)
			(layer "B.Fab")
		)
		(fp_line
			(start 0.12065 0.2794)
			(end 0.12065 0.3048)
			(stroke
				(width 0.1)
				(type default)
			)
			(layer "B.Fab")
		)
		(fp_line
			(start -0.12065 -0.2794)
			(end -0.12065 -0.3048)
			(stroke
				(width 0.1)
				(type default)
			)
			(layer "B.Fab")
		)
		(fp_line
			(start 0.12065 -0.2794)
			(end -0.12065 -0.2794)
			(stroke
				(width 0.1)
				(type default)
			)
			(layer "B.Fab")
		)
		(fp_line
			(start -0.67945 -0.3048)
			(end -0.67945 0.3048)
			(stroke
				(width 0.1)
				(type default)
			)
			(layer "B.Fab")
		)
		(fp_line
			(start -0.12065 -0.3048)
			(end -0.67945 -0.3048)
			(stroke
				(width 0.1)
				(type default)
			)
			(layer "B.Fab")
		)
		(fp_line
			(start 0.12065 -0.305054)
			(end 0.12065 -0.2794)
			(stroke
				(width 0.1)
				(type default)
			)
			(layer "B.Fab")
		)
		(fp_line
			(start 0.67945 -0.305054)
			(end 0.12065 -0.305054)
			(stroke
				(width 0.1)
				(type default)
			)
			(layer "B.Fab")
		)
		(pad "1" smd circle
			(at 0.40005 0 90)
			(size 0 0)
			(layers "B.Cu" "B.Mask" "B.Paste")
			(net "P3V3_AUX")
		)
		(pad "2" smd circle
			(at -0.40005 0 90)
			(size 0 0)
			(layers "B.Cu" "B.Mask" "B.Paste")
			(net "P3V3_AUX_USB_HUB")
		)
	)
	(footprint ""
		(layer "B.Cu")
		(at 384.87858 -395.148562 90)
		(property "Reference" "C1015"
			(at 0 0 90)
			(layer "B.SilkS")
			(hide yes)
			(effects
				(font
					(size 1.27 1.27)
				)
				(justify mirror)
			)
		)
		(property "Value" ""
			(at 0 0 90)
			(layer "B.Fab")
			(effects
				(font
					(size 1.27 1.27)
				)
				(justify mirror)
			)
		)
		(duplicate_pad_numbers_are_jumpers no)
		(fp_line
			(start 0.299974 -0.150114)
			(end -0.299974 -0.150114)
			(stroke
				(width 0.1)
				(type default)
			)
			(layer "B.Fab")
		)
		(fp_line
			(start -0.299974 -0.150114)
			(end -0.299974 0.150114)
			(stroke
				(width 0.1)
				(type default)
			)
			(layer "B.Fab")
		)
		(fp_line
			(start 0.299974 0.150114)
			(end 0.299974 -0.150114)
			(stroke
				(width 0.1)
				(type default)
			)
			(layer "B.Fab")
		)
		(fp_line
			(start -0.299974 0.150114)
			(end 0.299974 0.150114)
			(stroke
				(width 0.1)
				(type default)
			)
			(layer "B.Fab")
		)
		(pad "1" smd rect
			(at 0.2667 0 270)
			(size 0.3048 0.381)
			(layers "B.Cu" "B.Mask" "B.Paste")
			(net "P0V9_CPU0_RT3_2A")
		)
		(pad "2" smd rect
			(at -0.2667 0 270)
			(size 0.3048 0.381)
			(layers "B.Cu" "B.Mask" "B.Paste")
			(net "GND")
		)
	)
	(footprint ""
		(layer "B.Cu")
		(at 383.67843 -395.148562 90)
		(property "Reference" "C1018"
			(at 0 0 90)
			(layer "B.SilkS")
			(hide yes)
			(effects
				(font
					(size 1.27 1.27)
				)
				(justify mirror)
			)
		)
		(property "Value" ""
			(at 0 0 90)
			(layer "B.Fab")
			(effects
				(font
					(size 1.27 1.27)
				)
				(justify mirror)
			)
		)
		(duplicate_pad_numbers_are_jumpers no)
		(fp_line
			(start 0.299974 -0.150114)
			(end -0.299974 -0.150114)
			(stroke
				(width 0.1)
				(type default)
			)
			(layer "B.Fab")
		)
		(fp_line
			(start -0.299974 -0.150114)
			(end -0.299974 0.150114)
			(stroke
				(width 0.1)
				(type default)
			)
			(layer "B.Fab")
		)
		(fp_line
			(start 0.299974 0.150114)
			(end 0.299974 -0.150114)
			(stroke
				(width 0.1)
				(type default)
			)
			(layer "B.Fab")
		)
		(fp_line
			(start -0.299974 0.150114)
			(end 0.299974 0.150114)
			(stroke
				(width 0.1)
				(type default)
			)
			(layer "B.Fab")
		)
		(pad "1" smd rect
			(at 0.2667 0 270)
			(size 0.3048 0.381)
			(layers "B.Cu" "B.Mask" "B.Paste")
			(net "P0V9_CPU0_RT3_2A_2D")
		)
		(pad "2" smd rect
			(at -0.2667 0 270)
			(size 0.3048 0.381)
			(layers "B.Cu" "B.Mask" "B.Paste")
			(net "GND")
		)
	)
	(footprint ""
		(layer "B.Cu")
		(at 187.325 -426.212 -90)
		(property "Reference" "U8006"
			(at -0.208534 -6.062472 270)
			(unlocked yes)
			(layer "B.SilkS")
			(effects
				(font
					(size 0.7874 0.5842)
					(thickness 0.1524)
				)
				(justify mirror)
			)
		)
		(property "Value" ""
			(at 0 0 90)
			(layer "B.Fab")
			(effects
				(font
					(size 1.27 1.27)
				)
				(justify mirror)
			)
		)
		(duplicate_pad_numbers_are_jumpers no)
		(fp_line
			(start -2.032 1.549908)
			(end 2.032 1.549908)
			(stroke
				(width 0.1524)
				(type default)
			)
			(layer "B.SilkS")
		)
		(fp_line
			(start 2.032 1.549908)
			(end 2.032 -1.549908)
			(stroke
				(width 0.1524)
				(type default)
			)
			(layer "B.SilkS")
		)
		(fp_line
			(start 0 -0.762)
			(end -0.508 -1.549908)
			(stroke
				(width 0.1524)
				(type default)
			)
			(layer "B.SilkS")
		)
		(fp_line
			(start -2.032 -1.549908)
			(end -2.032 1.549908)
			(stroke
				(width 0.1524)
				(type default)
			)
			(layer "B.SilkS")
		)
		(fp_line
			(start -0.508 -1.549908)
			(end -2.032 -1.549908)
			(stroke
				(width 0.1524)
				(type default)
			)
			(layer "B.SilkS")
		)
		(fp_line
			(start 0.508 -1.549908)
			(end 0 -0.762)
			(stroke
				(width 0.1524)
				(type default)
			)
			(layer "B.SilkS")
		)
		(fp_line
			(start 2.032 -1.549908)
			(end 0.508 -1.549908)
			(stroke
				(width 0.1524)
				(type default)
			)
			(layer "B.SilkS")
		)
		(fp_poly
			(pts
				(xy 2.036572 -2.90957) (xy 2.864358 -2.320544) (xy 1.861566 -1.787144)
			)
			(stroke
				(width 0)
				(type default)
			)
			(fill yes)
			(layer "B.SilkS")
		)
		(fp_line
			(start -0.849884 1.549908)
			(end 0.849884 1.549908)
			(stroke
				(width 0.1)
				(type default)
			)
			(layer "B.Fab")
		)
		(fp_line
			(start 0.849884 1.549908)
			(end 0.849884 -1.549908)
			(stroke
				(width 0.1)
				(type default)
			)
			(layer "B.Fab")
		)
		(fp_line
			(start -0.849884 -1.549908)
			(end -0.849884 1.549908)
			(stroke
				(width 0.1)
				(type default)
			)
			(layer "B.Fab")
		)
		(fp_line
			(start 0.849884 -1.549908)
			(end -0.849884 -1.549908)
			(stroke
				(width 0.1)
				(type default)
			)
			(layer "B.Fab")
		)
		(fp_poly
			(pts
				(xy 3.2004 -1.45796) (xy 3.2004 -0.44196) (xy 2.1844 -0.94996)
			)
			(stroke
				(width 0)
				(type default)
			)
			(fill yes)
			(layer "B.Fab")
		)
		(pad "1" smd rect
			(at 1.35001 -0.94996 180)
			(size 0.6096 1.0668)
			(layers "B.Cu" "B.Mask" "B.Paste")
			(net "OC_P2V5_COMP")
		)
		(pad "2" smd rect
			(at 1.35001 0 180)
			(size 0.6096 1.0668)
			(layers "B.Cu" "B.Mask" "B.Paste")
			(net "GND")
		)
		(pad "3" smd rect
			(at 1.35001 0.94996 180)
			(size 0.6096 1.0668)
			(layers "B.Cu" "B.Mask" "B.Paste")
			(net "HSC_OC_VOL")
		)
		(pad "4" smd rect
			(at -1.35001 0.94996 180)
			(size 0.6096 1.0668)
			(layers "B.Cu" "B.Mask" "B.Paste")
			(net "HSC_D_OC_R2")
		)
		(pad "5" smd rect
			(at -1.35001 -0.94996 180)
			(size 0.6096 1.0668)
			(layers "B.Cu" "B.Mask" "B.Paste")
			(net "P12V_AUX")
		)
	)
	(footprint ""
		(layer "B.Cu")
		(at 31.623 -361.569 -90)
		(property "Reference" "PR12"
			(at 0 0 90)
			(layer "B.SilkS")
			(hide yes)
			(effects
				(font
					(size 1.27 1.27)
				)
				(justify mirror)
			)
		)
		(property "Value" ""
			(at 0 0 90)
			(layer "B.Fab")
			(effects
				(font
					(size 1.27 1.27)
				)
				(justify mirror)
			)
		)
		(duplicate_pad_numbers_are_jumpers no)
		(fp_line
			(start -0.7874 0.4064)
			(end 0.7874 0.4064)
			(stroke
				(width 0.1524)
				(type default)
			)
			(layer "B.SilkS")
		)
		(fp_line
			(start 0.7874 0.4064)
			(end 0.7874 -0.4064)
			(stroke
				(width 0.1524)
				(type default)
			)
			(layer "B.SilkS")
		)
		(fp_line
			(start -0.7874 -0.4064)
			(end -0.7874 0.4064)
			(stroke
				(width 0.1524)
				(type default)
			)
			(layer "B.SilkS")
		)
		(fp_line
			(start 0.7874 -0.4064)
			(end -0.7874 -0.4064)
			(stroke
				(width 0.1524)
				(type default)
			)
			(layer "B.SilkS")
		)
		(fp_line
			(start -0.67945 0.3048)
			(end -0.120396 0.3048)
			(stroke
				(width 0.1)
				(type default)
			)
			(layer "B.Fab")
		)
		(fp_line
			(start -0.120396 0.3048)
			(end -0.120396 0.2794)
			(stroke
				(width 0.1)
				(type default)
			)
			(layer "B.Fab")
		)
		(fp_line
			(start 0.12065 0.3048)
			(end 0.67945 0.3048)
			(stroke
				(width 0.1)
				(type default)
			)
			(layer "B.Fab")
		)
		(fp_line
			(start 0.67945 0.3048)
			(end 0.67945 -0.305054)
			(stroke
				(width 0.1)
				(type default)
			)
			(layer "B.Fab")
		)
		(fp_line
			(start -0.120396 0.2794)
			(end 0.12065 0.2794)
			(stroke
				(width 0.1)
				(type default)
			)
			(layer "B.Fab")
		)
		(fp_line
			(start 0.12065 0.2794)
			(end 0.12065 0.3048)
			(stroke
				(width 0.1)
				(type default)
			)
			(layer "B.Fab")
		)
		(fp_line
			(start -0.12065 -0.2794)
			(end -0.12065 -0.3048)
			(stroke
				(width 0.1)
				(type default)
			)
			(layer "B.Fab")
		)
		(fp_line
			(start 0.12065 -0.2794)
			(end -0.12065 -0.2794)
			(stroke
				(width 0.1)
				(type default)
			)
			(layer "B.Fab")
		)
		(fp_line
			(start -0.67945 -0.3048)
			(end -0.67945 0.3048)
			(stroke
				(width 0.1)
				(type default)
			)
			(layer "B.Fab")
		)
		(fp_line
			(start -0.12065 -0.3048)
			(end -0.67945 -0.3048)
			(stroke
				(width 0.1)
				(type default)
			)
			(layer "B.Fab")
		)
		(fp_line
			(start 0.12065 -0.305054)
			(end 0.12065 -0.2794)
			(stroke
				(width 0.1)
				(type default)
			)
			(layer "B.Fab")
		)
		(fp_line
			(start 0.67945 -0.305054)
			(end 0.12065 -0.305054)
			(stroke
				(width 0.1)
				(type default)
			)
			(layer "B.Fab")
		)
		(pad "1" smd circle
			(at 0.40005 0 90)
			(size 0 0)
			(layers "B.Cu" "B.Mask" "B.Paste")
			(net "NC_PVDDCR_CPU1_P1_IMON8")
		)
		(pad "2" smd circle
			(at -0.40005 0 90)
			(size 0 0)
			(layers "B.Cu" "B.Mask" "B.Paste")
			(net "GND")
		)
	)
)
